FILE_TYPE = CONNECTIVITY;
{Allegro Design Entry HDL 17.4-2019 S026 (4007227) 1/17/2022}
"PAGE_NUMBER" = 457;
0"NC";
END.
